(
  (version 16.5)
  (tool
    (creator "conceptHDL")
    (last "conceptHDL")
  )
  (library "mstr_symbols")
  (design "p12v"
    (lastIds
      (lastNetId 4)
    )
    (nets
      ("N1" "g" -1 -1 1 3)
      ("N2" "page1_g" -1 -1 0 )
      ("N4" "page1_p12v" -1 -1 0 )
      ("N3" "p12v" -1 -1 2 )
    )

    (alias
      ("N2" -1 -1 "N1" -1 -1)
      ("N4" -1 -1 "N2" -1 -1)
      ("N4" -1 -1 "N3" -1 -1)
    )

  )
)
